( ConstraintFile "p5v"
	( constraintHeader
		( objectKey
			( logical )
		)
		( version
			( 16.5 )
		)
		( revisionNumber
			( logicalViewRevNum 2 )
			( physicalViewRevNum 0 )
			( otherViewRevNum 0 )
		)
		( contents
			( dictionaryExtensions )
			( worksheetCustomizations )
			( electricalConstraints )
			( netClasses )
			( properties )
		)
		( precision
			( units mil )
			( numberOfDecimalPlaces 2 )
		)
	)
	( DictionaryExtensions
		( Attribute
			( Name "MATERIAL" )
			( Description " " )
			( Value
				( DataType ( dString ) )
				( Status  sProperty  sPackage )
			)
			( Objects
				( ValidObjects  oGate  oGateDefn  oBlock  oPart  oDesign  oSystem  oPartDefn )
				( NoInherit
					( oGate oPin )
				)
			)
			( Analysis
			)
		)
		( Attribute
			( Name "TOLERANCE" )
			( Description " " )
			( Value
				( DataType ( dString ) )
				( Status  sProperty  sPackage )
			)
			( Objects
				( ValidObjects  oGate  oGateDefn  oBlock  oPart  oDesign  oSystem  oPartDefn )
				( NoInherit
					( oGate oPin )
				)
			)
			( Analysis
			)
		)
		( Attribute
			( Name "WATTAGE" )
			( Description " " )
			( Value
				( DataType ( dString ) )
				( Status  sProperty  sPackage )
			)
			( Objects
				( ValidObjects  oGate  oGateDefn  oBlock  oPart  oDesign  oSystem  oPartDefn )
				( NoInherit
					( oGate oPin )
				)
			)
			( Analysis
			)
		)
		( Attribute
			( Name "CDS_LMAN_SYM_OUTLINE" )
			( Description " " )
			( Value
				( DataType ( dString ) )
				( Status  sProperty  sPackage )
			)
			( Objects
				( ValidObjects  oGate  oGateDefn  oBlock  oPart  oDesign  oSystem  oPartDefn )
				( NoInherit
					( oGate oPin )
				)
			)
			( Analysis
			)
		)
		( Attribute
			( Name "SEC_TYPE" )
			( Description " " )
			( Value
				( DataType ( dString ) )
				( Status  sProperty  sPackage )
			)
			( Objects
				( ValidObjects  oGate  oGateDefn  oBlock  oPart  oDesign  oSystem  oPartDefn )
				( NoInherit
					( oGate oPin )
				)
			)
			( Analysis
			)
		)
		( Attribute
			( Name "$sec" )
			( Description "" )
			( Value
				( DataType ( dString ) )
				( Status  sProperty )
			)
			( Objects
				( ValidObjects  oAll )
			)
			( Analysis
			)
		)
		( Attribute
			( Name "$location" )
			( Description "" )
			( Value
				( DataType ( dString ) )
				( Status  sProperty )
			)
			( Objects
				( ValidObjects  oAll )
			)
			( Analysis
			)
		)
		( Attribute
			( Name "WACKO" )
			( Description " " )
			( Value
				( DataType ( dString ) )
				( Status  sProperty  sPackage )
			)
			( Objects
				( ValidObjects  oGate  oGateDefn  oBlock  oPart  oDesign  oSystem  oPartDefn )
				( NoInherit
					( oGate oPin )
				)
			)
			( Analysis
			)
		)
		( Attribute
			( Name "BODY_TYPE" )
			( Description " " )
			( Value
				( DataType ( dString ) )
				( Status  sProperty  sPackage )
			)
			( Objects
				( ValidObjects  oGate  oBlock  oPart  oDesign  oSystem  oGateDefn  oPartDefn )
			)
			( Analysis
			)
		)
	)
	( designConstraints
		( ruleChanges
			( allRules )
			( design "p5v"
			)
			( signal "@mstr_symbols.p5v(sch_1):g"
				( objectFlag fObjectAlias )
				( objectStatus "g" )
			)
			( signal "@mstr_symbols.p5v(sch_1):page1_g"
				( objectFlag fObjectAlias )
				( objectStatus "page1_g" )
			)
			( signal "@mstr_symbols.p5v(sch_1):p5v"
				( alias ( signalRef "@mstr_symbols.p5v(sch_1):page1_p5v") )
				( alias ( signalRef "@mstr_symbols.p5v(sch_1):page1_g") )
				( alias ( signalRef "@mstr_symbols.p5v(sch_1):g") )
				( objectStatus "p5v" )
			)
			( signal "@mstr_symbols.p5v(sch_1):page1_p5v"
				( objectFlag fObjectAlias )
				( objectStatus "page1_p5v" )
			)
		)
	)
)
